(kicad_pcb
	(version 20260206)
	(generator "pcbnew")
	(generator_version "10.0")
	(general
		(thickness 1.6)
		(legacy_teardrops no)
	)
	(paper "A4")
	(title_block
		(title "04192023_DAF0TMB3IC0_F0TG_MB_C_brd_V02_OCP.brd")
		(comment 1 "Grand Teton / footprints 5318-5324 of 8354")
	)
	(layers
		(0 "F.Cu" signal "TOP")
		(4 "In1.Cu" signal "GND")
		(6 "In2.Cu" signal "IN1")
		(8 "In3.Cu" signal "GND1")
		(10 "In4.Cu" signal "IN2")
		(12 "In5.Cu" signal "GND2")
		(14 "In6.Cu" signal "IN3")
		(16 "In7.Cu" signal "GND3")
		(18 "In8.Cu" signal "VCC")
		(20 "In9.Cu" signal "VCC1")
		(22 "In10.Cu" signal "GND4")
		(24 "In11.Cu" signal "IN4")
		(26 "In12.Cu" signal "GND5")
		(28 "In13.Cu" signal "IN5")
		(30 "In14.Cu" signal "GND6")
		(32 "In15.Cu" signal "IN6")
		(34 "In16.Cu" signal "GND7")
		(2 "B.Cu" signal "BOTTOM")
		(9 "F.Adhes" user "F.Adhesive")
		(11 "B.Adhes" user "B.Adhesive")
		(13 "F.Paste" user "Package Geometry/Pastemask Top")
		(15 "B.Paste" user "Package Geometry/Pastemask Bottom")
		(5 "F.SilkS" user "Ref Des/Silkscreen Top")
		(7 "B.SilkS" user "Ref Des/Silkscreen Bottom")
		(1 "F.Mask" user "Board Geometry/Soldermask Top")
		(3 "B.Mask" user "Board Geometry/Soldermask Bottom")
		(17 "Dwgs.User" user "User.Drawings")
		(19 "Cmts.User" user "User.Comments")
		(21 "Eco1.User" user "User.Eco1")
		(23 "Eco2.User" user "User.Eco2")
		(25 "Edge.Cuts" user "Board Geometry/Outline")
		(27 "Margin" user)
		(31 "F.CrtYd" user "Package Geometry/Place Bound Top")
		(29 "B.CrtYd" user "Package Geometry/Place Bound Bottom")
		(35 "F.Fab" user "Ref Des/Assembly Top")
		(33 "B.Fab" user "Ref Des/Assembly Bottom")
	)
	(footprint ""
		(layer "B.Cu")
		(at 343.39022 -169.787062 90)
		(property "Reference" "PC163_6"
			(at 0 0 90)
			(layer "B.SilkS")
			(hide yes)
			(effects
				(font
					(size 1.27 1.27)
				)
				(justify mirror)
			)
		)
		(property "Value" ""
			(at 0 0 90)
			(layer "B.Fab")
			(effects
				(font
					(size 1.27 1.27)
				)
				(justify mirror)
			)
		)
		(duplicate_pad_numbers_are_jumpers no)
		(fp_line
			(start 1.524 -0.762)
			(end -1.524 -0.762)
			(stroke
				(width 0.1524)
				(type default)
			)
			(layer "B.SilkS")
		)
		(fp_line
			(start -1.524 -0.762)
			(end -1.524 0.762)
			(stroke
				(width 0.1524)
				(type default)
			)
			(layer "B.SilkS")
		)
		(fp_line
			(start 1.524 0.762)
			(end 1.524 -0.762)
			(stroke
				(width 0.1524)
				(type default)
			)
			(layer "B.SilkS")
		)
		(fp_line
			(start -1.524 0.762)
			(end 1.524 0.762)
			(stroke
				(width 0.1524)
				(type default)
			)
			(layer "B.SilkS")
		)
		(fp_line
			(start 1.1049 -0.724916)
			(end 1.1049 0.724916)
			(stroke
				(width 0.1)
				(type default)
			)
			(layer "B.Fab")
		)
		(fp_line
			(start -1.1049 -0.724916)
			(end 1.1049 -0.724916)
			(stroke
				(width 0.1)
				(type default)
			)
			(layer "B.Fab")
		)
		(fp_line
			(start 1.1049 0.724916)
			(end -1.1049 0.724916)
			(stroke
				(width 0.1)
				(type default)
			)
			(layer "B.Fab")
		)
		(fp_line
			(start -1.1049 0.724916)
			(end -1.1049 -0.724916)
			(stroke
				(width 0.1)
				(type default)
			)
			(layer "B.Fab")
		)
		(pad "1" smd rect
			(at 0.889 0 90)
			(size 1.016 1.27)
			(layers "B.Cu" "B.Mask" "B.Paste")
			(net "PVDDCR_CPU0_P0")
		)
		(pad "2" smd rect
			(at -0.889 0 90)
			(size 1.016 1.27)
			(layers "B.Cu" "B.Mask" "B.Paste")
			(net "GND")
		)
	)
	(footprint ""
		(layer "B.Cu")
		(at 138.65352 -40.765222 180)
		(property "Reference" "C6070"
			(at 0 0 0)
			(layer "B.SilkS")
			(hide yes)
			(effects
				(font
					(size 1.27 1.27)
				)
				(justify mirror)
			)
		)
		(property "Value" ""
			(at 0 0 0)
			(layer "B.Fab")
			(effects
				(font
					(size 1.27 1.27)
				)
				(justify mirror)
			)
		)
		(duplicate_pad_numbers_are_jumpers no)
		(fp_line
			(start 0.7874 0.4064)
			(end 0.7874 -0.4064)
			(stroke
				(width 0.1524)
				(type default)
			)
			(layer "B.SilkS")
		)
		(fp_line
			(start 0.7874 -0.4064)
			(end -0.7874 -0.4064)
			(stroke
				(width 0.1524)
				(type default)
			)
			(layer "B.SilkS")
		)
		(fp_line
			(start -0.7874 0.4064)
			(end 0.7874 0.4064)
			(stroke
				(width 0.1524)
				(type default)
			)
			(layer "B.SilkS")
		)
		(fp_line
			(start -0.7874 -0.4064)
			(end -0.7874 0.4064)
			(stroke
				(width 0.1524)
				(type default)
			)
			(layer "B.SilkS")
		)
		(fp_line
			(start 0.67945 0.3048)
			(end 0.67945 -0.305054)
			(stroke
				(width 0.1)
				(type default)
			)
			(layer "B.Fab")
		)
		(fp_line
			(start 0.67945 -0.305054)
			(end 0.12065 -0.305054)
			(stroke
				(width 0.1)
				(type default)
			)
			(layer "B.Fab")
		)
		(fp_line
			(start 0.12065 0.3048)
			(end 0.67945 0.3048)
			(stroke
				(width 0.1)
				(type default)
			)
			(layer "B.Fab")
		)
		(fp_line
			(start 0.12065 0.2794)
			(end 0.12065 0.3048)
			(stroke
				(width 0.1)
				(type default)
			)
			(layer "B.Fab")
		)
		(fp_line
			(start 0.12065 -0.2794)
			(end -0.12065 -0.2794)
			(stroke
				(width 0.1)
				(type default)
			)
			(layer "B.Fab")
		)
		(fp_line
			(start 0.12065 -0.305054)
			(end 0.12065 -0.2794)
			(stroke
				(width 0.1)
				(type default)
			)
			(layer "B.Fab")
		)
		(fp_line
			(start -0.120396 0.3048)
			(end -0.120396 0.2794)
			(stroke
				(width 0.1)
				(type default)
			)
			(layer "B.Fab")
		)
		(fp_line
			(start -0.120396 0.2794)
			(end 0.12065 0.2794)
			(stroke
				(width 0.1)
				(type default)
			)
			(layer "B.Fab")
		)
		(fp_line
			(start -0.12065 -0.2794)
			(end -0.12065 -0.3048)
			(stroke
				(width 0.1)
				(type default)
			)
			(layer "B.Fab")
		)
		(fp_line
			(start -0.12065 -0.3048)
			(end -0.67945 -0.3048)
			(stroke
				(width 0.1)
				(type default)
			)
			(layer "B.Fab")
		)
		(fp_line
			(start -0.67945 0.3048)
			(end -0.120396 0.3048)
			(stroke
				(width 0.1)
				(type default)
			)
			(layer "B.Fab")
		)
		(fp_line
			(start -0.67945 -0.3048)
			(end -0.67945 0.3048)
			(stroke
				(width 0.1)
				(type default)
			)
			(layer "B.Fab")
		)
		(pad "1" smd circle
			(at 0.40005 0)
			(size 0 0)
			(layers "B.Cu" "B.Mask" "B.Paste")
			(net "P1V2_AUX")
		)
		(pad "2" smd circle
			(at -0.40005 0)
			(size 0 0)
			(layers "B.Cu" "B.Mask" "B.Paste")
			(net "GND")
		)
	)
	(footprint ""
		(layer "B.Cu")
		(at 160.69183 -16.77416)
		(property "Reference" "R4152"
			(at 0 0 0)
			(layer "B.SilkS")
			(hide yes)
			(effects
				(font
					(size 1.27 1.27)
				)
				(justify mirror)
			)
		)
		(property "Value" ""
			(at 0 0 0)
			(layer "B.Fab")
			(effects
				(font
					(size 1.27 1.27)
				)
				(justify mirror)
			)
		)
		(duplicate_pad_numbers_are_jumpers no)
		(fp_line
			(start -0.7874 -0.4064)
			(end -0.7874 0.4064)
			(stroke
				(width 0.1524)
				(type default)
			)
			(layer "B.SilkS")
		)
		(fp_line
			(start -0.7874 0.4064)
			(end 0.7874 0.4064)
			(stroke
				(width 0.1524)
				(type default)
			)
			(layer "B.SilkS")
		)
		(fp_line
			(start 0.7874 -0.4064)
			(end -0.7874 -0.4064)
			(stroke
				(width 0.1524)
				(type default)
			)
			(layer "B.SilkS")
		)
		(fp_line
			(start 0.7874 0.4064)
			(end 0.7874 -0.4064)
			(stroke
				(width 0.1524)
				(type default)
			)
			(layer "B.SilkS")
		)
		(fp_line
			(start -0.67945 -0.3048)
			(end -0.67945 0.3048)
			(stroke
				(width 0.1)
				(type default)
			)
			(layer "B.Fab")
		)
		(fp_line
			(start -0.67945 0.3048)
			(end -0.120396 0.3048)
			(stroke
				(width 0.1)
				(type default)
			)
			(layer "B.Fab")
		)
		(fp_line
			(start -0.12065 -0.3048)
			(end -0.67945 -0.3048)
			(stroke
				(width 0.1)
				(type default)
			)
			(layer "B.Fab")
		)
		(fp_line
			(start -0.12065 -0.2794)
			(end -0.12065 -0.3048)
			(stroke
				(width 0.1)
				(type default)
			)
			(layer "B.Fab")
		)
		(fp_line
			(start -0.120396 0.2794)
			(end 0.12065 0.2794)
			(stroke
				(width 0.1)
				(type default)
			)
			(layer "B.Fab")
		)
		(fp_line
			(start -0.120396 0.3048)
			(end -0.120396 0.2794)
			(stroke
				(width 0.1)
				(type default)
			)
			(layer "B.Fab")
		)
		(fp_line
			(start 0.12065 -0.305054)
			(end 0.12065 -0.2794)
			(stroke
				(width 0.1)
				(type default)
			)
			(layer "B.Fab")
		)
		(fp_line
			(start 0.12065 -0.2794)
			(end -0.12065 -0.2794)
			(stroke
				(width 0.1)
				(type default)
			)
			(layer "B.Fab")
		)
		(fp_line
			(start 0.12065 0.2794)
			(end 0.12065 0.3048)
			(stroke
				(width 0.1)
				(type default)
			)
			(layer "B.Fab")
		)
		(fp_line
			(start 0.12065 0.3048)
			(end 0.67945 0.3048)
			(stroke
				(width 0.1)
				(type default)
			)
			(layer "B.Fab")
		)
		(fp_line
			(start 0.67945 -0.305054)
			(end 0.12065 -0.305054)
			(stroke
				(width 0.1)
				(type default)
			)
			(layer "B.Fab")
		)
		(fp_line
			(start 0.67945 0.3048)
			(end 0.67945 -0.305054)
			(stroke
				(width 0.1)
				(type default)
			)
			(layer "B.Fab")
		)
		(pad "1" smd circle
			(at 0.40005 0 180)
			(size 0 0)
			(layers "B.Cu" "B.Mask" "B.Paste")
			(net "SMB_1_PLD_3V3AUX_SDA")
		)
		(pad "2" smd circle
			(at -0.40005 0 180)
			(size 0 0)
			(layers "B.Cu" "B.Mask" "B.Paste")
			(net "SMB_2_PLD_3V3AUX_SDA_R1")
		)
	)
	(footprint ""
		(layer "B.Cu")
		(at 61.553344 -408.517344 90)
		(property "Reference" "C6670"
			(at 0 0 90)
			(layer "B.SilkS")
			(hide yes)
			(effects
				(font
					(size 1.27 1.27)
				)
				(justify mirror)
			)
		)
		(property "Value" ""
			(at 0 0 90)
			(layer "B.Fab")
			(effects
				(font
					(size 1.27 1.27)
				)
				(justify mirror)
			)
		)
		(duplicate_pad_numbers_are_jumpers no)
		(fp_line
			(start 0.299974 -0.150114)
			(end -0.299974 -0.150114)
			(stroke
				(width 0.1)
				(type default)
			)
			(layer "B.Fab")
		)
		(fp_line
			(start -0.299974 -0.150114)
			(end -0.299974 0.150114)
			(stroke
				(width 0.1)
				(type default)
			)
			(layer "B.Fab")
		)
		(fp_line
			(start 0.299974 0.150114)
			(end 0.299974 -0.150114)
			(stroke
				(width 0.1)
				(type default)
			)
			(layer "B.Fab")
		)
		(fp_line
			(start -0.299974 0.150114)
			(end 0.299974 0.150114)
			(stroke
				(width 0.1)
				(type default)
			)
			(layer "B.Fab")
		)
		(pad "1" smd rect
			(at 0.2667 0 270)
			(size 0.3048 0.381)
			(layers "B.Cu" "B.Mask" "B.Paste")
			(net "P5E_CPU1_P1_TX_BUF_C_DN<4>")
		)
		(pad "2" smd rect
			(at -0.2667 0 270)
			(size 0.3048 0.381)
			(layers "B.Cu" "B.Mask" "B.Paste")
			(net "P5E_CPU1_P1_TX_BUF_DN<4>")
		)
	)
	(footprint ""
		(layer "B.Cu")
		(at 74.5236 -383.7432 180)
		(property "Reference" "R755"
			(at 0 0 0)
			(layer "B.SilkS")
			(hide yes)
			(effects
				(font
					(size 1.27 1.27)
				)
				(justify mirror)
			)
		)
		(property "Value" ""
			(at 0 0 0)
			(layer "B.Fab")
			(effects
				(font
					(size 1.27 1.27)
				)
				(justify mirror)
			)
		)
		(duplicate_pad_numbers_are_jumpers no)
		(fp_line
			(start 0.32512 0.175006)
			(end 0.32512 -0.175006)
			(stroke
				(width 0.1)
				(type default)
			)
			(layer "B.Fab")
		)
		(fp_line
			(start 0.32512 -0.175006)
			(end -0.32512 -0.175006)
			(stroke
				(width 0.1)
				(type default)
			)
			(layer "B.Fab")
		)
		(fp_line
			(start -0.32512 0.175006)
			(end 0.32512 0.175006)
			(stroke
				(width 0.1)
				(type default)
			)
			(layer "B.Fab")
		)
		(fp_line
			(start -0.32512 -0.175006)
			(end -0.32512 0.175006)
			(stroke
				(width 0.1)
				(type default)
			)
			(layer "B.Fab")
		)
		(pad "1" smd rect
			(at 0.2667 0)
			(size 0.3048 0.381)
			(layers "B.Cu" "B.Mask" "B.Paste")
			(net "P1V8_CPU1_RT_1D")
		)
		(pad "2" smd rect
			(at -0.2667 0 180)
			(size 0.3048 0.381)
			(layers "B.Cu" "B.Mask" "B.Paste")
			(net "RT_CPU1_P1_SCAN_MODE")
		)
	)
	(footprint ""
		(layer "B.Cu")
		(at 181.872382 -20.378166 90)
		(property "Reference" "R2419"
			(at 0 0 90)
			(layer "B.SilkS")
			(hide yes)
			(effects
				(font
					(size 1.27 1.27)
				)
				(justify mirror)
			)
		)
		(property "Value" ""
			(at 0 0 90)
			(layer "B.Fab")
			(effects
				(font
					(size 1.27 1.27)
				)
				(justify mirror)
			)
		)
		(duplicate_pad_numbers_are_jumpers no)
		(fp_line
			(start 0.7874 -0.4064)
			(end -0.7874 -0.4064)
			(stroke
				(width 0.1524)
				(type default)
			)
			(layer "B.SilkS")
		)
		(fp_line
			(start -0.7874 -0.4064)
			(end -0.7874 0.4064)
			(stroke
				(width 0.1524)
				(type default)
			)
			(layer "B.SilkS")
		)
		(fp_line
			(start 0.7874 0.4064)
			(end 0.7874 -0.4064)
			(stroke
				(width 0.1524)
				(type default)
			)
			(layer "B.SilkS")
		)
		(fp_line
			(start -0.7874 0.4064)
			(end 0.7874 0.4064)
			(stroke
				(width 0.1524)
				(type default)
			)
			(layer "B.SilkS")
		)
		(fp_line
			(start 0.67945 -0.305054)
			(end 0.12065 -0.305054)
			(stroke
				(width 0.1)
				(type default)
			)
			(layer "B.Fab")
		)
		(fp_line
			(start 0.12065 -0.305054)
			(end 0.12065 -0.2794)
			(stroke
				(width 0.1)
				(type default)
			)
			(layer "B.Fab")
		)
		(fp_line
			(start -0.12065 -0.3048)
			(end -0.67945 -0.3048)
			(stroke
				(width 0.1)
				(type default)
			)
			(layer "B.Fab")
		)
		(fp_line
			(start -0.67945 -0.3048)
			(end -0.67945 0.3048)
			(stroke
				(width 0.1)
				(type default)
			)
			(layer "B.Fab")
		)
		(fp_line
			(start 0.12065 -0.2794)
			(end -0.12065 -0.2794)
			(stroke
				(width 0.1)
				(type default)
			)
			(layer "B.Fab")
		)
		(fp_line
			(start -0.12065 -0.2794)
			(end -0.12065 -0.3048)
			(stroke
				(width 0.1)
				(type default)
			)
			(layer "B.Fab")
		)
		(fp_line
			(start 0.12065 0.2794)
			(end 0.12065 0.3048)
			(stroke
				(width 0.1)
				(type default)
			)
			(layer "B.Fab")
		)
		(fp_line
			(start -0.120396 0.2794)
			(end 0.12065 0.2794)
			(stroke
				(width 0.1)
				(type default)
			)
			(layer "B.Fab")
		)
		(fp_line
			(start 0.67945 0.3048)
			(end 0.67945 -0.305054)
			(stroke
				(width 0.1)
				(type default)
			)
			(layer "B.Fab")
		)
		(fp_line
			(start 0.12065 0.3048)
			(end 0.67945 0.3048)
			(stroke
				(width 0.1)
				(type default)
			)
			(layer "B.Fab")
		)
		(fp_line
			(start -0.120396 0.3048)
			(end -0.120396 0.2794)
			(stroke
				(width 0.1)
				(type default)
			)
			(layer "B.Fab")
		)
		(fp_line
			(start -0.67945 0.3048)
			(end -0.120396 0.3048)
			(stroke
				(width 0.1)
				(type default)
			)
			(layer "B.Fab")
		)
		(pad "1" smd circle
			(at 0.40005 0 270)
			(size 0 0)
			(layers "B.Cu" "B.Mask" "B.Paste")
			(net "SMB_CPU0_CPU1_APML_SCL")
		)
		(pad "2" smd circle
			(at -0.40005 0 270)
			(size 0 0)
			(layers "B.Cu" "B.Mask" "B.Paste")
			(net "SMB_CPU0_CPU1_APML_SCL_R")
		)
	)
	(footprint ""
		(layer "B.Cu")
		(at 158.90113 -13.127228 180)
		(property "Reference" "R3113"
			(at 0 0 0)
			(layer "B.SilkS")
			(hide yes)
			(effects
				(font
					(size 1.27 1.27)
				)
				(justify mirror)
			)
		)
		(property "Value" ""
			(at 0 0 0)
			(layer "B.Fab")
			(effects
				(font
					(size 1.27 1.27)
				)
				(justify mirror)
			)
		)
		(duplicate_pad_numbers_are_jumpers no)
		(fp_line
			(start 0.7874 0.4064)
			(end 0.7874 -0.4064)
			(stroke
				(width 0.1524)
				(type default)
			)
			(layer "B.SilkS")
		)
		(fp_line
			(start 0.7874 -0.4064)
			(end -0.7874 -0.4064)
			(stroke
				(width 0.1524)
				(type default)
			)
			(layer "B.SilkS")
		)
		(fp_line
			(start -0.7874 0.4064)
			(end 0.7874 0.4064)
			(stroke
				(width 0.1524)
				(type default)
			)
			(layer "B.SilkS")
		)
		(fp_line
			(start -0.7874 -0.4064)
			(end -0.7874 0.4064)
			(stroke
				(width 0.1524)
				(type default)
			)
			(layer "B.SilkS")
		)
		(fp_line
			(start 0.67945 0.3048)
			(end 0.67945 -0.305054)
			(stroke
				(width 0.1)
				(type default)
			)
			(layer "B.Fab")
		)
		(fp_line
			(start 0.67945 -0.305054)
			(end 0.12065 -0.305054)
			(stroke
				(width 0.1)
				(type default)
			)
			(layer "B.Fab")
		)
		(fp_line
			(start 0.12065 0.3048)
			(end 0.67945 0.3048)
			(stroke
				(width 0.1)
				(type default)
			)
			(layer "B.Fab")
		)
		(fp_line
			(start 0.12065 0.2794)
			(end 0.12065 0.3048)
			(stroke
				(width 0.1)
				(type default)
			)
			(layer "B.Fab")
		)
		(fp_line
			(start 0.12065 -0.2794)
			(end -0.12065 -0.2794)
			(stroke
				(width 0.1)
				(type default)
			)
			(layer "B.Fab")
		)
		(fp_line
			(start 0.12065 -0.305054)
			(end 0.12065 -0.2794)
			(stroke
				(width 0.1)
				(type default)
			)
			(layer "B.Fab")
		)
		(fp_line
			(start -0.120396 0.3048)
			(end -0.120396 0.2794)
			(stroke
				(width 0.1)
				(type default)
			)
			(layer "B.Fab")
		)
		(fp_line
			(start -0.120396 0.2794)
			(end 0.12065 0.2794)
			(stroke
				(width 0.1)
				(type default)
			)
			(layer "B.Fab")
		)
		(fp_line
			(start -0.12065 -0.2794)
			(end -0.12065 -0.3048)
			(stroke
				(width 0.1)
				(type default)
			)
			(layer "B.Fab")
		)
		(fp_line
			(start -0.12065 -0.3048)
			(end -0.67945 -0.3048)
			(stroke
				(width 0.1)
				(type default)
			)
			(layer "B.Fab")
		)
		(fp_line
			(start -0.67945 0.3048)
			(end -0.120396 0.3048)
			(stroke
				(width 0.1)
				(type default)
			)
			(layer "B.Fab")
		)
		(fp_line
			(start -0.67945 -0.3048)
			(end -0.67945 0.3048)
			(stroke
				(width 0.1)
				(type default)
			)
			(layer "B.Fab")
		)
		(pad "1" smd circle
			(at 0.40005 0)
			(size 0 0)
			(layers "B.Cu" "B.Mask" "B.Paste")
			(net "SMB_FAN_3V3AUX_SCL")
		)
		(pad "2" smd circle
			(at -0.40005 0)
			(size 0 0)
			(layers "B.Cu" "B.Mask" "B.Paste")
			(net "SMB_FAN_3V3AUX_R_SCL")
		)
	)
)
